# BASEBOARD_FAB2 (Tioga Pass) — schematic netlist excerpt (pin names and nets, part order shuffled) for the footprints in the layout excerpt that follows; sources: Cadence DE-HDL packaged netlist, KiCad conversion of Wiwynn_Tioga_Pass_MB.brd

C1D28  CAP_A  0.1UF 16V 10% X7R  pkg 0402V  page 208 : A = VR_FET_SW_P12V_STBY_PVCCIN_CPU1 ; B = GND
RT17  RES  0 5.0% CHIP  pkg 0603  page 207 : A = VR_PVCCIN_CPU1_PH2_BOOT ; B = VR_PVCCIN_CPU1_PH2_BOOT_R
C1G23  CAP_A  1.0UF 6.3V 10% X6S  pkg 0402V  page 223 : A = VR_PVDDQ_GHJ_VD12 ; B = GND

(kicad_pcb
	(version 20260206)
	(generator "pcbnew")
	(generator_version "10.0")
	(general
		(thickness 1.6)
		(legacy_teardrops no)
	)
	(paper "A4")
	(title_block
		(title "Wiwynn_Tioga_Pass_MB.brd")
		(comment 1 "Tioga Pass / footprints 389-391 of 4770")
	)
	(layers
		(0 "F.Cu" signal "TOP")
		(4 "In1.Cu" signal "L2GND")
		(6 "In2.Cu" signal "L3")
		(8 "In3.Cu" signal "L4GND")
		(10 "In4.Cu" signal "L5")
		(12 "In5.Cu" signal "L6GND")
		(14 "In6.Cu" signal "L7VCC")
		(16 "In7.Cu" signal "L8VCC")
		(18 "In8.Cu" signal "L9GND")
		(20 "In9.Cu" signal "L10")
		(22 "In10.Cu" signal "L11GND")
		(24 "In11.Cu" signal "L12")
		(26 "In12.Cu" signal "L13GND")
		(2 "B.Cu" signal "BOTTOM")
		(9 "F.Adhes" user "F.Adhesive")
		(11 "B.Adhes" user "B.Adhesive")
		(13 "F.Paste" user "Package Geometry/Pastemask Top")
		(15 "B.Paste" user "Package Geometry/Pastemask Bottom")
		(5 "F.SilkS" user "Ref Des/Silkscreen Top")
		(7 "B.SilkS" user "Ref Des/Silkscreen Bottom")
		(1 "F.Mask" user "Board Geometry/Soldermask Top")
		(3 "B.Mask" user "Board Geometry/Soldermask Bottom")
		(17 "Dwgs.User" user "User.Drawings")
		(19 "Cmts.User" user "User.Comments")
		(21 "Eco1.User" user "User.Eco1")
		(23 "Eco2.User" user "User.Eco2")
		(25 "Edge.Cuts" user "Board Geometry/Outline")
		(27 "Margin" user)
		(31 "F.CrtYd" user "Package Geometry/Place Bound Top")
		(29 "B.CrtYd" user "Package Geometry/Place Bound Bottom")
		(35 "F.Fab" user "Ref Des/Assembly Top")
		(33 "B.Fab" user "Ref Des/Assembly Bottom")
	)
	(footprint ""
		(layer "F.Cu")
		(at 13.941806 3.507232 90)
		(property "Reference" "C1G23"
			(at 0 0 90)
			(layer "F.SilkS")
			(hide yes)
			(effects
				(font
					(size 1.27 1.27)
				)
			)
		)
		(property "Value" ""
			(at 0 0 90)
			(layer "F.Fab")
			(effects
				(font
					(size 1.27 1.27)
				)
			)
		)
		(duplicate_pad_numbers_are_jumpers no)
		(fp_poly
			(pts
				(xy 0.3048 -0.1016) (xy 0.3048 0.9906) (xy -0.3048 0.9906) (xy -0.3048 -0.1016)
			)
			(stroke
				(width 0)
				(type default)
			)
			(fill no)
			(layer "F.CrtYd")
		)
		(fp_line
			(start 0.3048 -0.1016)
			(end -0.3048 -0.1016)
			(stroke
				(width 0.1)
				(type default)
			)
			(layer "F.Fab")
		)
		(fp_line
			(start -0.3048 -0.1016)
			(end -0.3048 0.9906)
			(stroke
				(width 0.1)
				(type default)
			)
			(layer "F.Fab")
		)
		(fp_line
			(start 0.3048 0.9906)
			(end 0.3048 -0.1016)
			(stroke
				(width 0.1)
				(type default)
			)
			(layer "F.Fab")
		)
		(fp_line
			(start -0.3048 0.9906)
			(end 0.3048 0.9906)
			(stroke
				(width 0.1)
				(type default)
			)
			(layer "F.Fab")
		)
		(pad "1" smd rect
			(at 0 0 90)
			(size 0.508 0.508)
			(layers "F.Cu" "F.Mask" "F.Paste")
			(net "VR_PVDDQ_GHJ_VD12")
		)
		(pad "2" smd rect
			(at 0 0.889 90)
			(size 0.508 0.508)
			(layers "F.Cu" "F.Mask" "F.Paste")
			(net "GND")
		)
		(zone
			(layer "F.Cu")
			(hatch none 0.5)
			(connect_pads
				(clearance 0)
			)
			(min_thickness 0.25)
			(keepout
				(tracks allowed)
				(vias not_allowed)
				(pads allowed)
				(copperpour not_allowed)
				(footprints allowed)
			)
			(placement
				(enabled no)
				(sheetname "")
			)
			(fill
				(thermal_gap 0.5)
				(thermal_bridge_width 0.5)
				(island_removal_mode 0)
			)
			(polygon
				(pts
					(xy 14.195806 3.761232) (xy 14.195806 3.253232) (xy 14.576806 3.253232) (xy 14.576806 3.761232)
				)
			)
		)
		(zone
			(layer "F.Cu")
			(hatch none 0.5)
			(connect_pads
				(clearance 0)
			)
			(min_thickness 0.25)
			(keepout
				(tracks not_allowed)
				(vias allowed)
				(pads allowed)
				(copperpour not_allowed)
				(footprints allowed)
			)
			(placement
				(enabled no)
				(sheetname "")
			)
			(fill
				(thermal_gap 0.5)
				(thermal_bridge_width 0.5)
				(island_removal_mode 0)
			)
			(polygon
				(pts
					(xy 14.576806 3.761232) (xy 14.576806 3.253232) (xy 14.195806 3.253232) (xy 14.195806 3.761232)
				)
			)
		)
	)
	(footprint ""
		(layer "F.Cu")
		(at 33.2105 -76.708 90)
		(property "Reference" "C1D28"
			(at 0 0 90)
			(layer "F.SilkS")
			(hide yes)
			(effects
				(font
					(size 1.27 1.27)
				)
			)
		)
		(property "Value" ""
			(at 0 0 90)
			(layer "F.Fab")
			(effects
				(font
					(size 1.27 1.27)
				)
			)
		)
		(duplicate_pad_numbers_are_jumpers no)
		(fp_rect
			(start 0.3048 0.9906)
			(end -0.3048 -0.1016)
			(stroke
				(width 0)
				(type default)
			)
			(fill no)
			(layer "F.CrtYd")
		)
		(fp_line
			(start 0.3048 -0.1016)
			(end -0.3048 -0.1016)
			(stroke
				(width 0.1)
				(type default)
			)
			(layer "F.Fab")
		)
		(fp_line
			(start -0.3048 -0.1016)
			(end -0.3048 0.9906)
			(stroke
				(width 0.1)
				(type default)
			)
			(layer "F.Fab")
		)
		(fp_line
			(start 0.3048 0.9906)
			(end 0.3048 -0.1016)
			(stroke
				(width 0.1)
				(type default)
			)
			(layer "F.Fab")
		)
		(fp_line
			(start -0.3048 0.9906)
			(end 0.3048 0.9906)
			(stroke
				(width 0.1)
				(type default)
			)
			(layer "F.Fab")
		)
		(pad "1" smd rect
			(at 0 0 90)
			(size 0.508 0.508)
			(layers "F.Cu" "F.Mask" "F.Paste")
			(net "VR_FET_SW_P12V_STBY_PVCCIN_CPU1")
		)
		(pad "2" smd rect
			(at 0 0.889 90)
			(size 0.508 0.508)
			(layers "F.Cu" "F.Mask" "F.Paste")
			(net "GND")
		)
		(zone
			(layer "F.Cu")
			(hatch none 0.5)
			(connect_pads
				(clearance 0)
			)
			(min_thickness 0.25)
			(keepout
				(tracks not_allowed)
				(vias allowed)
				(pads allowed)
				(copperpour not_allowed)
				(footprints allowed)
			)
			(placement
				(enabled no)
				(sheetname "")
			)
			(fill
				(thermal_gap 0.5)
				(thermal_bridge_width 0.5)
				(island_removal_mode 0)
			)
			(polygon
				(pts
					(xy 33.8455 -76.962) (xy 33.4645 -76.962) (xy 33.4645 -76.454) (xy 33.8455 -76.454)
				)
			)
		)
		(zone
			(layer "F.Cu")
			(hatch none 0.5)
			(connect_pads
				(clearance 0)
			)
			(min_thickness 0.25)
			(keepout
				(tracks allowed)
				(vias not_allowed)
				(pads allowed)
				(copperpour not_allowed)
				(footprints allowed)
			)
			(placement
				(enabled no)
				(sheetname "")
			)
			(fill
				(thermal_gap 0.5)
				(thermal_bridge_width 0.5)
				(island_removal_mode 0)
			)
			(polygon
				(pts
					(xy 33.8455 -76.962) (xy 33.4645 -76.962) (xy 33.4645 -76.454) (xy 33.8455 -76.454)
				)
			)
		)
	)
	(footprint ""
		(layer "F.Cu")
		(at 27.559 -65.913 90)
		(property "Reference" "RT17"
			(at 1.01473 0.656336 0)
			(unlocked yes)
			(layer "F.SilkS")
			(effects
				(font
					(size 0.4064 0.254)
					(thickness 0.1524)
				)
			)
		)
		(property "Value" ""
			(at 0 0 90)
			(layer "F.Fab")
			(effects
				(font
					(size 1.27 1.27)
				)
			)
		)
		(duplicate_pad_numbers_are_jumpers no)
		(fp_poly
			(pts
				(xy -0.4953 -0.2032) (xy 0.4953 -0.2032) (xy 0.4953 1.6002) (xy -0.4953 1.6002)
			)
			(stroke
				(width 0)
				(type default)
			)
			(fill no)
			(layer "F.CrtYd")
		)
		(fp_line
			(start 0.4953 -0.2032)
			(end 0.4953 1.6002)
			(stroke
				(width 0.1)
				(type default)
			)
			(layer "F.Fab")
		)
		(fp_line
			(start -0.4953 -0.2032)
			(end 0.4953 -0.2032)
			(stroke
				(width 0.1)
				(type default)
			)
			(layer "F.Fab")
		)
		(fp_line
			(start 0.4953 1.6002)
			(end -0.4953 1.6002)
			(stroke
				(width 0.1)
				(type default)
			)
			(layer "F.Fab")
		)
		(fp_line
			(start -0.4953 1.6002)
			(end -0.4953 -0.2032)
			(stroke
				(width 0.1)
				(type default)
			)
			(layer "F.Fab")
		)
		(pad "1" smd rect
			(at 0 0 90)
			(size 0.762 0.889)
			(layers "F.Cu" "F.Mask" "F.Paste")
			(net "VR_PVCCIN_CPU1_PH2_BOOT")
		)
		(pad "2" smd rect
			(at 0 1.397 90)
			(size 0.762 0.889)
			(layers "F.Cu" "F.Mask" "F.Paste")
			(net "VR_PVCCIN_CPU1_PH2_BOOT_R")
		)
		(zone
			(layer "F.Cu")
			(hatch none 0.5)
			(connect_pads
				(clearance 0)
			)
			(min_thickness 0.25)
			(keepout
				(tracks allowed)
				(vias not_allowed)
				(pads allowed)
				(copperpour not_allowed)
				(footprints allowed)
			)
			(placement
				(enabled no)
				(sheetname "")
			)
			(fill
				(thermal_gap 0.5)
				(thermal_bridge_width 0.5)
				(island_removal_mode 0)
			)
			(polygon
				(pts
					(xy 28.5115 -66.294) (xy 28.0035 -66.294) (xy 28.0035 -65.532) (xy 28.5115 -65.532)
				)
			)
		)
		(zone
			(layer "F.Cu")
			(hatch none 0.5)
			(connect_pads
				(clearance 0)
			)
			(min_thickness 0.25)
			(keepout
				(tracks not_allowed)
				(vias allowed)
				(pads allowed)
				(copperpour not_allowed)
				(footprints allowed)
			)
			(placement
				(enabled no)
				(sheetname "")
			)
			(fill
				(thermal_gap 0.5)
				(thermal_bridge_width 0.5)
				(island_removal_mode 0)
			)
			(polygon
				(pts
					(xy 28.5115 -65.532) (xy 28.5115 -66.294) (xy 28.0035 -66.294) (xy 28.0035 -65.532)
				)
			)
		)
	)
)
